# TIMECARD (Time Appliance Project (Time Card)) — schematic netlist excerpt (pin names and nets, part order shuffled) for the footprints in the layout excerpt that follows; sources: Cadence DE-HDL packaged netlist, KiCad conversion of R4006-B0001-02_R01.brd

R323  RESISTOR  4.7KOHM 1%  pkg SMC_0402R_H016  page 26 : \1\ = UNNAMED_14_IS32FL3207QWLA3TRQ_1 ; \2\ = SG
C2  CAPACITOR  0.1UF 25V 10%  pkg SMC_0402R_H022  page 27 : \1\ = XP12R0V_IN ; \2\ = SG

(kicad_pcb
	(version 20260206)
	(generator "pcbnew")
	(generator_version "10.0")
	(general
		(thickness 1.6)
		(legacy_teardrops no)
	)
	(paper "A4")
	(title_block
		(title "timecard-production-celestica-r4006 — R4006-B0001-02_R01.brd")
		(comment 1 "Time Appliance Project (Time Card) / footprints 157-158 of 1113")
	)
	(layers
		(0 "F.Cu" signal "TOP")
		(4 "In1.Cu" signal "L02_GND1")
		(6 "In2.Cu" signal "L03_SIG1")
		(8 "In3.Cu" signal "L04_GND2")
		(10 "In4.Cu" signal "L05_VCC1")
		(12 "In5.Cu" signal "L06_VCC2")
		(14 "In6.Cu" signal "L07_GND3")
		(16 "In7.Cu" signal "L08_SIG2")
		(18 "In8.Cu" signal "L09_GND4")
		(2 "B.Cu" signal "BOTTOM")
		(9 "F.Adhes" user "F.Adhesive")
		(11 "B.Adhes" user "B.Adhesive")
		(13 "F.Paste" user "Package Geometry/Pastemask Top")
		(15 "B.Paste" user "Package Geometry/Pastemask Bottom")
		(5 "F.SilkS" user "Ref Des/Silkscreen Top")
		(7 "B.SilkS" user "Ref Des/Silkscreen Bottom")
		(1 "F.Mask" user "Board Geometry/Soldermask Top")
		(3 "B.Mask" user "Board Geometry/Soldermask Bottom")
		(17 "Dwgs.User" user "User.Drawings")
		(19 "Cmts.User" user "User.Comments")
		(21 "Eco1.User" user "User.Eco1")
		(23 "Eco2.User" user "User.Eco2")
		(25 "Edge.Cuts" user "Board Geometry/Outline")
		(27 "Margin" user)
		(31 "F.CrtYd" user "Package Geometry/Place Bound Top")
		(29 "B.CrtYd" user "Package Geometry/Place Bound Bottom")
		(35 "F.Fab" user "Ref Des/Assembly Top")
		(33 "B.Fab" user "Ref Des/Assembly Bottom")
	)
	(footprint ""
		(layer "F.Cu")
		(at 111.125 -101.981)
		(property "Reference" "R323"
			(at 3.175 -3.13563 0)
			(unlocked yes)
			(layer "F.SilkS")
			(effects
				(font
					(size 0.7874 0.5842)
					(thickness 0.1524)
				)
			)
		)
		(property "Value" "VAL*"
			(at 0.02032 2.13233 0)
			(unlocked yes)
			(layer "F.Fab")
			(hide yes)
			(effects
				(font
					(size 0.7874 0.5842)
					(thickness 0.1524)
				)
			)
		)
		(property "Tolerance" "TOL*"
			(at 0.044704 3.05435 0)
			(unlocked yes)
			(layer "Cmts.User")
			(hide yes)
			(effects
				(font
					(size 0.7874 0.5842)
					(thickness 0.1524)
				)
			)
		)
		(property "User Part Number" "PARTNUM*"
			(at 0.02032 4.024884 0)
			(unlocked yes)
			(layer "Cmts.User")
			(hide yes)
			(effects
				(font
					(size 0.7874 0.5842)
					(thickness 0.1524)
				)
			)
		)
		(property "Device Type" "RESISTOR-G155-14701-01,4.7KOHMA"
			(at 0.008382 1.210564 0)
			(unlocked yes)
			(layer "F.Fab")
			(hide yes)
			(effects
				(font
					(size 0.7874 0.5842)
					(thickness 0.1524)
				)
			)
		)
		(duplicate_pad_numbers_are_jumpers no)
		(fp_line
			(start -1.143 -0.5588)
			(end -1.143 0.5588)
			(stroke
				(width 0.1)
				(type default)
			)
			(layer "F.SilkS")
		)
		(fp_line
			(start -1.143 0.5588)
			(end 1.143 0.5588)
			(stroke
				(width 0.1)
				(type default)
			)
			(layer "F.SilkS")
		)
		(fp_line
			(start 1.143 -0.5588)
			(end -1.143 -0.5588)
			(stroke
				(width 0.1)
				(type default)
			)
			(layer "F.SilkS")
		)
		(fp_line
			(start 1.143 0.5588)
			(end 1.143 -0.5588)
			(stroke
				(width 0.1)
				(type default)
			)
			(layer "F.SilkS")
		)
		(fp_poly
			(pts
				(xy -1.143 0.5588) (xy 1.143 0.5588) (xy 1.143 -0.5588) (xy -1.143 -0.5588)
			)
			(stroke
				(width 0)
				(type default)
			)
			(fill no)
			(layer "F.CrtYd")
		)
		(fp_line
			(start -0.508 -0.3048)
			(end -0.508 0.3048)
			(stroke
				(width 0.1)
				(type default)
			)
			(layer "F.Fab")
		)
		(fp_line
			(start -0.508 0.3048)
			(end 0.508 0.3048)
			(stroke
				(width 0.1)
				(type default)
			)
			(layer "F.Fab")
		)
		(fp_line
			(start 0.508 -0.3048)
			(end -0.508 -0.3048)
			(stroke
				(width 0.1)
				(type default)
			)
			(layer "F.Fab")
		)
		(fp_line
			(start 0.508 0.3048)
			(end 0.508 -0.3048)
			(stroke
				(width 0.1)
				(type default)
			)
			(layer "F.Fab")
		)
		(pad "1" smd rect
			(at -0.5334 0)
			(size 0.7112 0.6096)
			(layers "F.Cu" "F.Mask" "F.Paste")
			(net "UNNAMED_14_IS32FL3207QWLA3TRQ_1")
		)
		(pad "2" smd rect
			(at 0.5334 0)
			(size 0.7112 0.6096)
			(layers "F.Cu" "F.Mask" "F.Paste")
			(net "SG")
		)
		(zone
			(layer "F.Cu")
			(hatch none 0.5)
			(connect_pads
				(clearance 0)
			)
			(min_thickness 0.25)
			(keepout
				(tracks allowed)
				(vias not_allowed)
				(pads allowed)
				(copperpour not_allowed)
				(footprints allowed)
			)
			(placement
				(enabled no)
				(sheetname "")
			)
			(fill
				(thermal_gap 0.5)
				(thermal_bridge_width 0.5)
				(island_removal_mode 0)
			)
			(polygon
				(pts
					(xy 111.0488 -101.6762) (xy 111.2012 -101.6762) (xy 111.2012 -102.2858) (xy 111.0488 -102.2858)
				)
			)
		)
		(zone
			(layer "F.Cu")
			(hatch none 0.5)
			(connect_pads
				(clearance 0)
			)
			(min_thickness 0.25)
			(keepout
				(tracks not_allowed)
				(vias allowed)
				(pads allowed)
				(copperpour not_allowed)
				(footprints allowed)
			)
			(placement
				(enabled no)
				(sheetname "")
			)
			(fill
				(thermal_gap 0.5)
				(thermal_bridge_width 0.5)
				(island_removal_mode 0)
			)
			(polygon
				(pts
					(xy 111.0488 -101.6762) (xy 111.2012 -101.6762) (xy 111.2012 -102.2858) (xy 111.0488 -102.2858)
				)
			)
		)
	)
	(footprint ""
		(layer "F.Cu")
		(at 142.6464 -90.6526)
		(property "Reference" "C2"
			(at -0.6604 1.15697 0)
			(unlocked yes)
			(layer "F.SilkS")
			(effects
				(font
					(size 0.7874 0.5842)
					(thickness 0.1524)
				)
			)
		)
		(property "Value" "VAL*"
			(at 0.0762 2.067306 0)
			(unlocked yes)
			(layer "F.Fab")
			(hide yes)
			(effects
				(font
					(size 0.7874 0.5842)
					(thickness 0.1524)
				)
			)
		)
		(property "Device Type" "CAPACITOR-G105-0B104-EK,0.1UF,A"
			(at 0.0508 1.127506 0)
			(unlocked yes)
			(layer "F.Fab")
			(hide yes)
			(effects
				(font
					(size 0.7874 0.5842)
					(thickness 0.1524)
				)
			)
		)
		(property "User Part Number" "PARTNUM*"
			(at 0.1016 4.023106 0)
			(unlocked yes)
			(layer "Cmts.User")
			(hide yes)
			(effects
				(font
					(size 0.7874 0.5842)
					(thickness 0.1524)
				)
			)
		)
		(property "Tolerance" "TOL*"
			(at 0.0762 3.032506 0)
			(unlocked yes)
			(layer "Cmts.User")
			(hide yes)
			(effects
				(font
					(size 0.7874 0.5842)
					(thickness 0.1524)
				)
			)
		)
		(duplicate_pad_numbers_are_jumpers no)
		(fp_line
			(start -1.143 -0.5588)
			(end -1.143 0.5588)
			(stroke
				(width 0.1)
				(type default)
			)
			(layer "F.SilkS")
		)
		(fp_line
			(start -1.143 0.5588)
			(end 1.143 0.5588)
			(stroke
				(width 0.1)
				(type default)
			)
			(layer "F.SilkS")
		)
		(fp_line
			(start 1.143 -0.5588)
			(end -1.143 -0.5588)
			(stroke
				(width 0.1)
				(type default)
			)
			(layer "F.SilkS")
		)
		(fp_line
			(start 1.143 0.5588)
			(end 1.143 -0.5588)
			(stroke
				(width 0.1)
				(type default)
			)
			(layer "F.SilkS")
		)
		(fp_rect
			(start -1.143 0.5588)
			(end 1.143 -0.5588)
			(stroke
				(width 0)
				(type default)
			)
			(fill no)
			(layer "F.CrtYd")
		)
		(fp_line
			(start -0.508 -0.3048)
			(end -0.508 0.3048)
			(stroke
				(width 0.1)
				(type default)
			)
			(layer "F.Fab")
		)
		(fp_line
			(start -0.508 0.3048)
			(end 0.508 0.3048)
			(stroke
				(width 0.1)
				(type default)
			)
			(layer "F.Fab")
		)
		(fp_line
			(start 0.508 -0.3048)
			(end -0.508 -0.3048)
			(stroke
				(width 0.1)
				(type default)
			)
			(layer "F.Fab")
		)
		(fp_line
			(start 0.508 0.3048)
			(end 0.508 -0.3048)
			(stroke
				(width 0.1)
				(type default)
			)
			(layer "F.Fab")
		)
		(pad "1" smd rect
			(at -0.5334 0)
			(size 0.7112 0.6096)
			(layers "F.Cu" "F.Mask" "F.Paste")
			(net "XP12R0V_IN")
		)
		(pad "2" smd rect
			(at 0.5334 0)
			(size 0.7112 0.6096)
			(layers "F.Cu" "F.Mask" "F.Paste")
			(net "SG")
		)
		(zone
			(layer "F.Cu")
			(hatch none 0.5)
			(connect_pads
				(clearance 0)
			)
			(min_thickness 0.25)
			(keepout
				(tracks allowed)
				(vias not_allowed)
				(pads allowed)
				(copperpour not_allowed)
				(footprints allowed)
			)
			(placement
				(enabled no)
				(sheetname "")
			)
			(fill
				(thermal_gap 0.5)
				(thermal_bridge_width 0.5)
				(island_removal_mode 0)
			)
			(polygon
				(pts
					(xy 142.5702 -90.3478) (xy 142.7226 -90.3478) (xy 142.7226 -90.9574) (xy 142.5702 -90.9574)
				)
			)
		)
	)
)
